# TIMECARD (Time Appliance Project (Time Card)) — schematic netlist excerpt (pin names and nets, part order shuffled) for the footprints in the layout excerpt that follows; sources: Cadence DE-HDL packaged netlist, KiCad conversion of R4006-B0001-02_R01.brd

R462  RESISTOR  33OHM 1%  pkg SMC_0402R_H016  page 24 : \1\ = FT4232_MUX2_SEL ; \2\ = MUX2_SEL
C20  CAPACITOR  22UF 10V 20%  pkg SMC_0805R_H057  page 28 : \1\ = XP3R3V ; \2\ = SG

(kicad_pcb
	(version 20260206)
	(generator "pcbnew")
	(generator_version "10.0")
	(general
		(thickness 1.6)
		(legacy_teardrops no)
	)
	(paper "A4")
	(title_block
		(title "timecard-production-celestica-r4006 — R4006-B0001-02_R01.brd")
		(comment 1 "Time Appliance Project (Time Card) / footprints 626-627 of 1113")
	)
	(layers
		(0 "F.Cu" signal "TOP")
		(4 "In1.Cu" signal "L02_GND1")
		(6 "In2.Cu" signal "L03_SIG1")
		(8 "In3.Cu" signal "L04_GND2")
		(10 "In4.Cu" signal "L05_VCC1")
		(12 "In5.Cu" signal "L06_VCC2")
		(14 "In6.Cu" signal "L07_GND3")
		(16 "In7.Cu" signal "L08_SIG2")
		(18 "In8.Cu" signal "L09_GND4")
		(2 "B.Cu" signal "BOTTOM")
		(9 "F.Adhes" user "F.Adhesive")
		(11 "B.Adhes" user "B.Adhesive")
		(13 "F.Paste" user "Package Geometry/Pastemask Top")
		(15 "B.Paste" user "Package Geometry/Pastemask Bottom")
		(5 "F.SilkS" user "Ref Des/Silkscreen Top")
		(7 "B.SilkS" user "Ref Des/Silkscreen Bottom")
		(1 "F.Mask" user "Board Geometry/Soldermask Top")
		(3 "B.Mask" user "Board Geometry/Soldermask Bottom")
		(17 "Dwgs.User" user "User.Drawings")
		(19 "Cmts.User" user "User.Comments")
		(21 "Eco1.User" user "User.Eco1")
		(23 "Eco2.User" user "User.Eco2")
		(25 "Edge.Cuts" user "Board Geometry/Outline")
		(27 "Margin" user)
		(31 "F.CrtYd" user "Package Geometry/Place Bound Top")
		(29 "B.CrtYd" user "Package Geometry/Place Bound Bottom")
		(35 "F.Fab" user "Ref Des/Assembly Top")
		(33 "B.Fab" user "Ref Des/Assembly Bottom")
	)
	(footprint ""
		(layer "F.Cu")
		(at 88.392 -93.599 90)
		(property "Reference" "C20"
			(at -3.81 -5.80263 90)
			(unlocked yes)
			(layer "F.SilkS")
			(effects
				(font
					(size 0.7874 0.5842)
					(thickness 0.1524)
				)
			)
		)
		(property "Value" "VAL*"
			(at 0.0762 3.134106 90)
			(unlocked yes)
			(layer "F.Fab")
			(hide yes)
			(effects
				(font
					(size 0.7874 0.5842)
					(thickness 0.1524)
				)
			)
		)
		(property "Tolerance" "TOL*"
			(at 0.0762 4.048506 90)
			(unlocked yes)
			(layer "Cmts.User")
			(hide yes)
			(effects
				(font
					(size 0.7874 0.5842)
					(thickness 0.1524)
				)
			)
		)
		(property "User Part Number" "PARTNUM*"
			(at 0.1016 5.013706 90)
			(unlocked yes)
			(layer "Cmts.User")
			(hide yes)
			(effects
				(font
					(size 0.7874 0.5842)
					(thickness 0.1524)
				)
			)
		)
		(property "Device Type" "CAPACITOR-G107-0F226-CM,22UF,2A"
			(at 0.0508 2.194306 90)
			(unlocked yes)
			(layer "F.Fab")
			(hide yes)
			(effects
				(font
					(size 0.7874 0.5842)
					(thickness 0.1524)
				)
			)
		)
		(duplicate_pad_numbers_are_jumpers no)
		(fp_line
			(start 1.5748 -0.9398)
			(end -1.5748 -0.9398)
			(stroke
				(width 0.1)
				(type default)
			)
			(layer "F.SilkS")
		)
		(fp_line
			(start -1.5748 -0.9398)
			(end -1.5748 0.9398)
			(stroke
				(width 0.1)
				(type default)
			)
			(layer "F.SilkS")
		)
		(fp_line
			(start 1.5748 0.9398)
			(end 1.5748 -0.9398)
			(stroke
				(width 0.1)
				(type default)
			)
			(layer "F.SilkS")
		)
		(fp_line
			(start -1.5748 0.9398)
			(end 1.5748 0.9398)
			(stroke
				(width 0.1)
				(type default)
			)
			(layer "F.SilkS")
		)
		(fp_rect
			(start 1.5748 0.9398)
			(end -1.5748 -0.9398)
			(stroke
				(width 0)
				(type default)
			)
			(fill no)
			(layer "F.CrtYd")
		)
		(fp_line
			(start 1.016 -0.635)
			(end -1.016 -0.635)
			(stroke
				(width 0.1)
				(type default)
			)
			(layer "F.Fab")
		)
		(fp_line
			(start -1.016 -0.635)
			(end -1.016 0.635)
			(stroke
				(width 0.1)
				(type default)
			)
			(layer "F.Fab")
		)
		(fp_line
			(start 1.016 0.635)
			(end 1.016 -0.635)
			(stroke
				(width 0.1)
				(type default)
			)
			(layer "F.Fab")
		)
		(fp_line
			(start -1.016 0.635)
			(end 1.016 0.635)
			(stroke
				(width 0.1)
				(type default)
			)
			(layer "F.Fab")
		)
		(pad "1" smd rect
			(at -0.8382 0 90)
			(size 0.9652 1.3716)
			(layers "F.Cu" "F.Mask" "F.Paste")
			(net "XP3R3V")
		)
		(pad "2" smd rect
			(at 0.8382 0 90)
			(size 0.9652 1.3716)
			(layers "F.Cu" "F.Mask" "F.Paste")
			(net "SG")
		)
		(zone
			(layer "F.Cu")
			(hatch none 0.5)
			(connect_pads
				(clearance 0)
			)
			(min_thickness 0.25)
			(keepout
				(tracks allowed)
				(vias not_allowed)
				(pads allowed)
				(copperpour not_allowed)
				(footprints allowed)
			)
			(placement
				(enabled no)
				(sheetname "")
			)
			(fill
				(thermal_gap 0.5)
				(thermal_bridge_width 0.5)
				(island_removal_mode 0)
			)
			(polygon
				(pts
					(xy 89.027 -93.8276) (xy 87.757 -93.8276) (xy 87.757 -93.3704) (xy 89.027 -93.3704)
				)
			)
		)
	)
	(footprint ""
		(layer "F.Cu")
		(at 101.4476 -82.2706)
		(property "Reference" "R462"
			(at -2.6416 0.77597 0)
			(unlocked yes)
			(layer "F.SilkS")
			(effects
				(font
					(size 0.7874 0.5842)
					(thickness 0.1524)
				)
			)
		)
		(property "Value" "VAL*"
			(at 0.02032 2.13233 0)
			(unlocked yes)
			(layer "F.Fab")
			(hide yes)
			(effects
				(font
					(size 0.7874 0.5842)
					(thickness 0.1524)
				)
			)
		)
		(property "Tolerance" "TOL*"
			(at 0.044704 3.05435 0)
			(unlocked yes)
			(layer "Cmts.User")
			(hide yes)
			(effects
				(font
					(size 0.7874 0.5842)
					(thickness 0.1524)
				)
			)
		)
		(property "User Part Number" "PARTNUM*"
			(at 0.02032 4.024884 0)
			(unlocked yes)
			(layer "Cmts.User")
			(hide yes)
			(effects
				(font
					(size 0.7874 0.5842)
					(thickness 0.1524)
				)
			)
		)
		(property "Device Type" "RESISTOR-G155-133R0-01,33OHM,1%"
			(at 0.008382 1.210564 0)
			(unlocked yes)
			(layer "F.Fab")
			(hide yes)
			(effects
				(font
					(size 0.7874 0.5842)
					(thickness 0.1524)
				)
			)
		)
		(duplicate_pad_numbers_are_jumpers no)
		(fp_line
			(start -1.143 -0.5588)
			(end -1.143 0.5588)
			(stroke
				(width 0.1)
				(type default)
			)
			(layer "F.SilkS")
		)
		(fp_line
			(start -1.143 0.5588)
			(end 1.143 0.5588)
			(stroke
				(width 0.1)
				(type default)
			)
			(layer "F.SilkS")
		)
		(fp_line
			(start 1.143 -0.5588)
			(end -1.143 -0.5588)
			(stroke
				(width 0.1)
				(type default)
			)
			(layer "F.SilkS")
		)
		(fp_line
			(start 1.143 0.5588)
			(end 1.143 -0.5588)
			(stroke
				(width 0.1)
				(type default)
			)
			(layer "F.SilkS")
		)
		(fp_poly
			(pts
				(xy -1.143 0.5588) (xy 1.143 0.5588) (xy 1.143 -0.5588) (xy -1.143 -0.5588)
			)
			(stroke
				(width 0)
				(type default)
			)
			(fill no)
			(layer "F.CrtYd")
		)
		(fp_line
			(start -0.508 -0.3048)
			(end -0.508 0.3048)
			(stroke
				(width 0.1)
				(type default)
			)
			(layer "F.Fab")
		)
		(fp_line
			(start -0.508 0.3048)
			(end 0.508 0.3048)
			(stroke
				(width 0.1)
				(type default)
			)
			(layer "F.Fab")
		)
		(fp_line
			(start 0.508 -0.3048)
			(end -0.508 -0.3048)
			(stroke
				(width 0.1)
				(type default)
			)
			(layer "F.Fab")
		)
		(fp_line
			(start 0.508 0.3048)
			(end 0.508 -0.3048)
			(stroke
				(width 0.1)
				(type default)
			)
			(layer "F.Fab")
		)
		(pad "1" smd rect
			(at -0.5334 0)
			(size 0.7112 0.6096)
			(layers "F.Cu" "F.Mask" "F.Paste")
			(net "FT4232_MUX2_SEL")
		)
		(pad "2" smd rect
			(at 0.5334 0)
			(size 0.7112 0.6096)
			(layers "F.Cu" "F.Mask" "F.Paste")
			(net "MUX2_SEL")
		)
		(zone
			(layer "F.Cu")
			(hatch none 0.5)
			(connect_pads
				(clearance 0)
			)
			(min_thickness 0.25)
			(keepout
				(tracks allowed)
				(vias not_allowed)
				(pads allowed)
				(copperpour not_allowed)
				(footprints allowed)
			)
			(placement
				(enabled no)
				(sheetname "")
			)
			(fill
				(thermal_gap 0.5)
				(thermal_bridge_width 0.5)
				(island_removal_mode 0)
			)
			(polygon
				(pts
					(xy 101.3714 -81.9658) (xy 101.5238 -81.9658) (xy 101.5238 -82.5754) (xy 101.3714 -82.5754)
				)
			)
		)
		(zone
			(layer "F.Cu")
			(hatch none 0.5)
			(connect_pads
				(clearance 0)
			)
			(min_thickness 0.25)
			(keepout
				(tracks not_allowed)
				(vias allowed)
				(pads allowed)
				(copperpour not_allowed)
				(footprints allowed)
			)
			(placement
				(enabled no)
				(sheetname "")
			)
			(fill
				(thermal_gap 0.5)
				(thermal_bridge_width 0.5)
				(island_removal_mode 0)
			)
			(polygon
				(pts
					(xy 101.3714 -81.9658) (xy 101.5238 -81.9658) (xy 101.5238 -82.5754) (xy 101.3714 -82.5754)
				)
			)
		)
	)
)
